# S9S_MB_2U (Grand Teton) — schematic netlist excerpt (pin names and nets, part order shuffled) for the footprints in the layout excerpt that follows; sources: Cadence DE-HDL packaged netlist, KiCad conversion of 03242023_DA0F0TMBIJ0_F0T_Motherboard_J_brd_V01_OCP.brd

U84  GTL2014PW  IC  pkg TSSOP14  page 239
  DIR  = PU_GTL2014_BMC_JTAG_DIR_1
  B0  = JTAG_DBP_PREQ_R_N
  B1  = FM_CPU_FBRK_DEBUG_N
  VREF  = PD_GTL2014_BMC_JTAG_VREF_1
  B2  = JTAG_DBP_FB_TDI
  B3  = JTAG_DBP_FB_TMS
  GND_0  = GND
  GND_1  = GND
  A3  = JTAG_BMC_DBP_TMS_R
  A2  = JTAG_BMC_DBP_TDI_R
  GND_2  = GND
  A1  = FM_BMC_CPU_FBRK_OUT_N
  A0  = JTAG_DBP_BMC_PREQ_R1_N
  VCC  = P3V3_AUX

C1713  Q_CAP  0.1UF 25V 10% X7R  pkg 0402  page 227 : A = P3V3_AUX ; B = GND

(kicad_pcb
	(version 20260206)
	(generator "pcbnew")
	(generator_version "10.0")
	(general
		(thickness 1.6)
		(legacy_teardrops no)
	)
	(paper "A4")
	(title_block
		(title "03242023_DA0F0TMBIJ0_F0T_Motherboard_J_brd_V01_OCP.brd")
		(comment 1 "Grand Teton / footprints 538-539 of 6105")
	)
	(layers
		(0 "F.Cu" signal "TOP")
		(4 "In1.Cu" signal "GND")
		(6 "In2.Cu" signal "IN1")
		(8 "In3.Cu" signal "GND1")
		(10 "In4.Cu" signal "IN2")
		(12 "In5.Cu" signal "GND2")
		(14 "In6.Cu" signal "IN3")
		(16 "In7.Cu" signal "GND3")
		(18 "In8.Cu" signal "VCC")
		(20 "In9.Cu" signal "VCC1")
		(22 "In10.Cu" signal "GND4")
		(24 "In11.Cu" signal "IN4")
		(26 "In12.Cu" signal "GND5")
		(28 "In13.Cu" signal "IN5")
		(30 "In14.Cu" signal "GND6")
		(32 "In15.Cu" signal "IN6")
		(34 "In16.Cu" signal "GND7")
		(2 "B.Cu" signal "BOTTOM")
		(9 "F.Adhes" user "F.Adhesive")
		(11 "B.Adhes" user "B.Adhesive")
		(13 "F.Paste" user "Package Geometry/Pastemask Top")
		(15 "B.Paste" user "Package Geometry/Pastemask Bottom")
		(5 "F.SilkS" user "Ref Des/Silkscreen Top")
		(7 "B.SilkS" user "Ref Des/Silkscreen Bottom")
		(1 "F.Mask" user "Board Geometry/Soldermask Top")
		(3 "B.Mask" user "Board Geometry/Soldermask Bottom")
		(17 "Dwgs.User" user "User.Drawings")
		(19 "Cmts.User" user "User.Comments")
		(21 "Eco1.User" user "User.Eco1")
		(23 "Eco2.User" user "User.Eco2")
		(25 "Edge.Cuts" user "Board Geometry/Outline")
		(27 "Margin" user)
		(31 "F.CrtYd" user "Package Geometry/Place Bound Top")
		(29 "B.CrtYd" user "Package Geometry/Place Bound Bottom")
		(35 "F.Fab" user "Ref Des/Assembly Top")
		(33 "B.Fab" user "Ref Des/Assembly Bottom")
	)
	(footprint ""
		(layer "F.Cu")
		(at 12.022582 -421.216836 90)
		(property "Reference" "C1713"
			(at 0 0 90)
			(layer "F.SilkS")
			(hide yes)
			(effects
				(font
					(size 1.27 1.27)
				)
			)
		)
		(property "Value" ""
			(at 0 0 90)
			(layer "F.Fab")
			(effects
				(font
					(size 1.27 1.27)
				)
			)
		)
		(duplicate_pad_numbers_are_jumpers no)
		(fp_line
			(start 0.7874 -0.4064)
			(end 0.7874 0.4064)
			(stroke
				(width 0.1524)
				(type default)
			)
			(layer "F.SilkS")
		)
		(fp_line
			(start -0.7874 -0.4064)
			(end 0.7874 -0.4064)
			(stroke
				(width 0.1524)
				(type default)
			)
			(layer "F.SilkS")
		)
		(fp_line
			(start 0.7874 0.4064)
			(end -0.7874 0.4064)
			(stroke
				(width 0.1524)
				(type default)
			)
			(layer "F.SilkS")
		)
		(fp_line
			(start -0.7874 0.4064)
			(end -0.7874 -0.4064)
			(stroke
				(width 0.1524)
				(type default)
			)
			(layer "F.SilkS")
		)
		(fp_line
			(start -0.12065 -0.305054)
			(end -0.12065 -0.2794)
			(stroke
				(width 0.1)
				(type default)
			)
			(layer "F.Fab")
		)
		(fp_line
			(start -0.67945 -0.305054)
			(end -0.12065 -0.305054)
			(stroke
				(width 0.1)
				(type default)
			)
			(layer "F.Fab")
		)
		(fp_line
			(start 0.67945 -0.3048)
			(end 0.67945 0.3048)
			(stroke
				(width 0.1)
				(type default)
			)
			(layer "F.Fab")
		)
		(fp_line
			(start 0.12065 -0.3048)
			(end 0.67945 -0.3048)
			(stroke
				(width 0.1)
				(type default)
			)
			(layer "F.Fab")
		)
		(fp_line
			(start 0.12065 -0.2794)
			(end 0.12065 -0.3048)
			(stroke
				(width 0.1)
				(type default)
			)
			(layer "F.Fab")
		)
		(fp_line
			(start -0.12065 -0.2794)
			(end 0.12065 -0.2794)
			(stroke
				(width 0.1)
				(type default)
			)
			(layer "F.Fab")
		)
		(fp_line
			(start 0.120396 0.2794)
			(end -0.12065 0.2794)
			(stroke
				(width 0.1)
				(type default)
			)
			(layer "F.Fab")
		)
		(fp_line
			(start -0.12065 0.2794)
			(end -0.12065 0.3048)
			(stroke
				(width 0.1)
				(type default)
			)
			(layer "F.Fab")
		)
		(fp_line
			(start 0.67945 0.3048)
			(end 0.120396 0.3048)
			(stroke
				(width 0.1)
				(type default)
			)
			(layer "F.Fab")
		)
		(fp_line
			(start 0.120396 0.3048)
			(end 0.120396 0.2794)
			(stroke
				(width 0.1)
				(type default)
			)
			(layer "F.Fab")
		)
		(fp_line
			(start -0.12065 0.3048)
			(end -0.67945 0.3048)
			(stroke
				(width 0.1)
				(type default)
			)
			(layer "F.Fab")
		)
		(fp_line
			(start -0.67945 0.3048)
			(end -0.67945 -0.305054)
			(stroke
				(width 0.1)
				(type default)
			)
			(layer "F.Fab")
		)
		(pad "1" smd circle
			(at -0.40005 0 90)
			(size 0 0)
			(layers "F.Cu" "F.Mask" "F.Paste")
			(net "P3V3_AUX")
		)
		(pad "2" smd circle
			(at 0.40005 0 90)
			(size 0 0)
			(layers "F.Cu" "F.Mask" "F.Paste")
			(net "GND")
		)
	)
	(footprint ""
		(layer "F.Cu")
		(at 371.672358 -99.185984 90)
		(property "Reference" "U84"
			(at 0.450596 -5.416042 0)
			(unlocked yes)
			(layer "F.SilkS")
			(effects
				(font
					(size 0.7874 0.5842)
					(thickness 0.1524)
				)
				(justify left)
			)
		)
		(property "Value" ""
			(at 0 0 90)
			(layer "F.Fab")
			(effects
				(font
					(size 1.27 1.27)
				)
			)
		)
		(duplicate_pad_numbers_are_jumpers no)
		(fp_line
			(start 2.0066 -2.5527)
			(end 2.0066 2.5527)
			(stroke
				(width 0.1524)
				(type default)
			)
			(layer "F.SilkS")
		)
		(fp_line
			(start 0.5715 -2.5527)
			(end 2.0066 -2.5527)
			(stroke
				(width 0.1524)
				(type default)
			)
			(layer "F.SilkS")
		)
		(fp_line
			(start -0.5715 -2.5527)
			(end 0 -1.9812)
			(stroke
				(width 0.1524)
				(type default)
			)
			(layer "F.SilkS")
		)
		(fp_line
			(start -2.0066 -2.5527)
			(end -0.5715 -2.5527)
			(stroke
				(width 0.1524)
				(type default)
			)
			(layer "F.SilkS")
		)
		(fp_line
			(start 0 -1.9812)
			(end 0.5715 -2.5527)
			(stroke
				(width 0.1524)
				(type default)
			)
			(layer "F.SilkS")
		)
		(fp_line
			(start 2.0066 2.5527)
			(end -2.0066 2.5527)
			(stroke
				(width 0.1524)
				(type default)
			)
			(layer "F.SilkS")
		)
		(fp_line
			(start -2.0066 2.5527)
			(end -2.0066 -2.5527)
			(stroke
				(width 0.1524)
				(type default)
			)
			(layer "F.SilkS")
		)
		(fp_poly
			(pts
				(xy -2.730246 -2.881122) (xy -3.058414 -2.327402) (xy -3.355086 -2.881122)
			)
			(stroke
				(width 0)
				(type default)
			)
			(fill yes)
			(layer "F.SilkS")
		)
		(fp_line
			(start 2.249932 -2.549906)
			(end 2.249932 2.549906)
			(stroke
				(width 0.1)
				(type default)
			)
			(layer "F.Fab")
		)
		(fp_line
			(start -2.249932 -2.549906)
			(end 2.249932 -2.549906)
			(stroke
				(width 0.1)
				(type default)
			)
			(layer "F.Fab")
		)
		(fp_line
			(start 2.249932 2.549906)
			(end -2.249932 2.549906)
			(stroke
				(width 0.1)
				(type default)
			)
			(layer "F.Fab")
		)
		(fp_line
			(start -2.249932 2.549906)
			(end -2.249932 -2.549906)
			(stroke
				(width 0.1)
				(type default)
			)
			(layer "F.Fab")
		)
		(fp_poly
			(pts
				(xy -4.36372 -1.608328) (xy -4.36372 -2.233168) (xy -3.81 -1.905)
			)
			(stroke
				(width 0)
				(type default)
			)
			(fill yes)
			(layer "F.Fab")
		)
		(pad "1" smd rect
			(at -2.921 -1.949958)
			(size 0.3556 1.4986)
			(layers "F.Cu" "F.Mask" "F.Paste")
			(net "PU_GTL2014_BMC_JTAG_DIR_1")
		)
		(pad "2" smd rect
			(at -2.921 -1.299972)
			(size 0.3556 1.4986)
			(layers "F.Cu" "F.Mask" "F.Paste")
			(net "JTAG_DBP_PREQ_R_N")
		)
		(pad "3" smd rect
			(at -2.921 -0.649986)
			(size 0.3556 1.4986)
			(layers "F.Cu" "F.Mask" "F.Paste")
			(net "FM_CPU_FBRK_DEBUG_N")
		)
		(pad "4" smd rect
			(at -2.921 0)
			(size 0.3556 1.4986)
			(layers "F.Cu" "F.Mask" "F.Paste")
			(net "PD_GTL2014_BMC_JTAG_VREF_1")
		)
		(pad "5" smd rect
			(at -2.921 0.649986)
			(size 0.3556 1.4986)
			(layers "F.Cu" "F.Mask" "F.Paste")
			(net "JTAG_DBP_FB_TDI")
		)
		(pad "6" smd rect
			(at -2.921 1.299972)
			(size 0.3556 1.4986)
			(layers "F.Cu" "F.Mask" "F.Paste")
			(net "JTAG_DBP_FB_TMS")
		)
		(pad "7" smd rect
			(at -2.921 1.949958)
			(size 0.3556 1.4986)
			(layers "F.Cu" "F.Mask" "F.Paste")
			(net "GND")
		)
		(pad "8" smd rect
			(at 2.921 1.949958)
			(size 0.3556 1.4986)
			(layers "F.Cu" "F.Mask" "F.Paste")
			(net "GND")
		)
		(pad "9" smd rect
			(at 2.921 1.299972)
			(size 0.3556 1.4986)
			(layers "F.Cu" "F.Mask" "F.Paste")
			(net "JTAG_BMC_DBP_TMS_R")
		)
		(pad "10" smd rect
			(at 2.921 0.649986)
			(size 0.3556 1.4986)
			(layers "F.Cu" "F.Mask" "F.Paste")
			(net "JTAG_BMC_DBP_TDI_R")
		)
		(pad "11" smd rect
			(at 2.921 0)
			(size 0.3556 1.4986)
			(layers "F.Cu" "F.Mask" "F.Paste")
			(net "GND")
		)
		(pad "12" smd rect
			(at 2.921 -0.649986)
			(size 0.3556 1.4986)
			(layers "F.Cu" "F.Mask" "F.Paste")
			(net "FM_BMC_CPU_FBRK_OUT_N")
		)
		(pad "13" smd rect
			(at 2.921 -1.299972)
			(size 0.3556 1.4986)
			(layers "F.Cu" "F.Mask" "F.Paste")
			(net "JTAG_DBP_BMC_PREQ_R1_N")
		)
		(pad "14" smd rect
			(at 2.921 -1.949958)
			(size 0.3556 1.4986)
			(layers "F.Cu" "F.Mask" "F.Paste")
			(net "P3V3_AUX")
		)
	)
)
